# S9S_MB_2U (Grand Teton) — schematic netlist excerpt (pin names and nets, part order shuffled) for the footprints in the layout excerpt that follows; sources: Cadence DE-HDL packaged netlist, KiCad conversion of 03242023_DA0F0TMBIJ0_F0T_Motherboard_J_brd_V01_OCP.brd

R4603  Q_RES  10K 1% CHIP  pkg 0402LF  page 234 : A = SMB_BMC_GPU_EN ; B = GND
C2195  Q_CAP  100PF 50V 5% EMPTY  pkg 0402  page 250 : A = P12V_E1S_0_ISENSE_MAM ; B = GND
C1883  Q_CAP  10UF 25V 10% X6S  pkg C0805  page 212 : A = VFG3P3_CLK_GEN ; B = GND

(kicad_pcb
	(version 20260206)
	(generator "pcbnew")
	(generator_version "10.0")
	(general
		(thickness 1.6)
		(legacy_teardrops no)
	)
	(paper "A4")
	(title_block
		(title "03242023_DA0F0TMBIJ0_F0T_Motherboard_J_brd_V01_OCP.brd")
		(comment 1 "Grand Teton / footprints 4580-4582 of 6105")
	)
	(layers
		(0 "F.Cu" signal "TOP")
		(4 "In1.Cu" signal "GND")
		(6 "In2.Cu" signal "IN1")
		(8 "In3.Cu" signal "GND1")
		(10 "In4.Cu" signal "IN2")
		(12 "In5.Cu" signal "GND2")
		(14 "In6.Cu" signal "IN3")
		(16 "In7.Cu" signal "GND3")
		(18 "In8.Cu" signal "VCC")
		(20 "In9.Cu" signal "VCC1")
		(22 "In10.Cu" signal "GND4")
		(24 "In11.Cu" signal "IN4")
		(26 "In12.Cu" signal "GND5")
		(28 "In13.Cu" signal "IN5")
		(30 "In14.Cu" signal "GND6")
		(32 "In15.Cu" signal "IN6")
		(34 "In16.Cu" signal "GND7")
		(2 "B.Cu" signal "BOTTOM")
		(9 "F.Adhes" user "F.Adhesive")
		(11 "B.Adhes" user "B.Adhesive")
		(13 "F.Paste" user "Package Geometry/Pastemask Top")
		(15 "B.Paste" user "Package Geometry/Pastemask Bottom")
		(5 "F.SilkS" user "Ref Des/Silkscreen Top")
		(7 "B.SilkS" user "Ref Des/Silkscreen Bottom")
		(1 "F.Mask" user "Board Geometry/Soldermask Top")
		(3 "B.Mask" user "Board Geometry/Soldermask Bottom")
		(17 "Dwgs.User" user "User.Drawings")
		(19 "Cmts.User" user "User.Comments")
		(21 "Eco1.User" user "User.Eco1")
		(23 "Eco2.User" user "User.Eco2")
		(25 "Edge.Cuts" user "Board Geometry/Outline")
		(27 "Margin" user)
		(31 "F.CrtYd" user "Package Geometry/Place Bound Top")
		(29 "B.CrtYd" user "Package Geometry/Place Bound Bottom")
		(35 "F.Fab" user "Ref Des/Assembly Top")
		(33 "B.Fab" user "Ref Des/Assembly Bottom")
	)
	(footprint ""
		(layer "B.Cu")
		(at 39.3954 -436.646828 -90)
		(property "Reference" "R4603"
			(at 0 0 90)
			(layer "B.SilkS")
			(hide yes)
			(effects
				(font
					(size 1.27 1.27)
				)
				(justify mirror)
			)
		)
		(property "Value" ""
			(at 0 0 90)
			(layer "B.Fab")
			(effects
				(font
					(size 1.27 1.27)
				)
				(justify mirror)
			)
		)
		(duplicate_pad_numbers_are_jumpers no)
		(fp_line
			(start -0.7874 0.4064)
			(end 0.7874 0.4064)
			(stroke
				(width 0.1524)
				(type default)
			)
			(layer "B.SilkS")
		)
		(fp_line
			(start 0.7874 0.4064)
			(end 0.7874 -0.4064)
			(stroke
				(width 0.1524)
				(type default)
			)
			(layer "B.SilkS")
		)
		(fp_line
			(start -0.7874 -0.4064)
			(end -0.7874 0.4064)
			(stroke
				(width 0.1524)
				(type default)
			)
			(layer "B.SilkS")
		)
		(fp_line
			(start 0.7874 -0.4064)
			(end -0.7874 -0.4064)
			(stroke
				(width 0.1524)
				(type default)
			)
			(layer "B.SilkS")
		)
		(fp_line
			(start -0.67945 0.3048)
			(end -0.120396 0.3048)
			(stroke
				(width 0.1)
				(type default)
			)
			(layer "B.Fab")
		)
		(fp_line
			(start -0.120396 0.3048)
			(end -0.120396 0.2794)
			(stroke
				(width 0.1)
				(type default)
			)
			(layer "B.Fab")
		)
		(fp_line
			(start 0.12065 0.3048)
			(end 0.67945 0.3048)
			(stroke
				(width 0.1)
				(type default)
			)
			(layer "B.Fab")
		)
		(fp_line
			(start 0.67945 0.3048)
			(end 0.67945 -0.305054)
			(stroke
				(width 0.1)
				(type default)
			)
			(layer "B.Fab")
		)
		(fp_line
			(start -0.120396 0.2794)
			(end 0.12065 0.2794)
			(stroke
				(width 0.1)
				(type default)
			)
			(layer "B.Fab")
		)
		(fp_line
			(start 0.12065 0.2794)
			(end 0.12065 0.3048)
			(stroke
				(width 0.1)
				(type default)
			)
			(layer "B.Fab")
		)
		(fp_line
			(start -0.12065 -0.2794)
			(end -0.12065 -0.3048)
			(stroke
				(width 0.1)
				(type default)
			)
			(layer "B.Fab")
		)
		(fp_line
			(start 0.12065 -0.2794)
			(end -0.12065 -0.2794)
			(stroke
				(width 0.1)
				(type default)
			)
			(layer "B.Fab")
		)
		(fp_line
			(start -0.67945 -0.3048)
			(end -0.67945 0.3048)
			(stroke
				(width 0.1)
				(type default)
			)
			(layer "B.Fab")
		)
		(fp_line
			(start -0.12065 -0.3048)
			(end -0.67945 -0.3048)
			(stroke
				(width 0.1)
				(type default)
			)
			(layer "B.Fab")
		)
		(fp_line
			(start 0.12065 -0.305054)
			(end 0.12065 -0.2794)
			(stroke
				(width 0.1)
				(type default)
			)
			(layer "B.Fab")
		)
		(fp_line
			(start 0.67945 -0.305054)
			(end 0.12065 -0.305054)
			(stroke
				(width 0.1)
				(type default)
			)
			(layer "B.Fab")
		)
		(pad "1" smd circle
			(at 0.40005 0 90)
			(size 0 0)
			(layers "B.Cu" "B.Mask" "B.Paste")
			(net "SMB_BMC_GPU_EN")
		)
		(pad "2" smd circle
			(at -0.40005 0 90)
			(size 0 0)
			(layers "B.Cu" "B.Mask" "B.Paste")
			(net "GND")
		)
	)
	(footprint ""
		(layer "B.Cu")
		(at 42.814748 -100.584762 -90)
		(property "Reference" "C2195"
			(at 0 0 90)
			(layer "B.SilkS")
			(hide yes)
			(effects
				(font
					(size 1.27 1.27)
				)
				(justify mirror)
			)
		)
		(property "Value" ""
			(at 0 0 90)
			(layer "B.Fab")
			(effects
				(font
					(size 1.27 1.27)
				)
				(justify mirror)
			)
		)
		(duplicate_pad_numbers_are_jumpers no)
		(fp_line
			(start -0.7874 0.4064)
			(end 0.7874 0.4064)
			(stroke
				(width 0.1524)
				(type default)
			)
			(layer "B.SilkS")
		)
		(fp_line
			(start 0.7874 0.4064)
			(end 0.7874 -0.4064)
			(stroke
				(width 0.1524)
				(type default)
			)
			(layer "B.SilkS")
		)
		(fp_line
			(start -0.7874 -0.4064)
			(end -0.7874 0.4064)
			(stroke
				(width 0.1524)
				(type default)
			)
			(layer "B.SilkS")
		)
		(fp_line
			(start 0.7874 -0.4064)
			(end -0.7874 -0.4064)
			(stroke
				(width 0.1524)
				(type default)
			)
			(layer "B.SilkS")
		)
		(fp_line
			(start -0.67945 0.3048)
			(end -0.120396 0.3048)
			(stroke
				(width 0.1)
				(type default)
			)
			(layer "B.Fab")
		)
		(fp_line
			(start -0.120396 0.3048)
			(end -0.120396 0.2794)
			(stroke
				(width 0.1)
				(type default)
			)
			(layer "B.Fab")
		)
		(fp_line
			(start 0.12065 0.3048)
			(end 0.67945 0.3048)
			(stroke
				(width 0.1)
				(type default)
			)
			(layer "B.Fab")
		)
		(fp_line
			(start 0.67945 0.3048)
			(end 0.67945 -0.305054)
			(stroke
				(width 0.1)
				(type default)
			)
			(layer "B.Fab")
		)
		(fp_line
			(start -0.120396 0.2794)
			(end 0.12065 0.2794)
			(stroke
				(width 0.1)
				(type default)
			)
			(layer "B.Fab")
		)
		(fp_line
			(start 0.12065 0.2794)
			(end 0.12065 0.3048)
			(stroke
				(width 0.1)
				(type default)
			)
			(layer "B.Fab")
		)
		(fp_line
			(start -0.12065 -0.2794)
			(end -0.12065 -0.3048)
			(stroke
				(width 0.1)
				(type default)
			)
			(layer "B.Fab")
		)
		(fp_line
			(start 0.12065 -0.2794)
			(end -0.12065 -0.2794)
			(stroke
				(width 0.1)
				(type default)
			)
			(layer "B.Fab")
		)
		(fp_line
			(start -0.67945 -0.3048)
			(end -0.67945 0.3048)
			(stroke
				(width 0.1)
				(type default)
			)
			(layer "B.Fab")
		)
		(fp_line
			(start -0.12065 -0.3048)
			(end -0.67945 -0.3048)
			(stroke
				(width 0.1)
				(type default)
			)
			(layer "B.Fab")
		)
		(fp_line
			(start 0.12065 -0.305054)
			(end 0.12065 -0.2794)
			(stroke
				(width 0.1)
				(type default)
			)
			(layer "B.Fab")
		)
		(fp_line
			(start 0.67945 -0.305054)
			(end 0.12065 -0.305054)
			(stroke
				(width 0.1)
				(type default)
			)
			(layer "B.Fab")
		)
		(pad "1" smd circle
			(at 0.40005 0 90)
			(size 0 0)
			(layers "B.Cu" "B.Mask" "B.Paste")
			(net "P12V_E1S_0_ISENSE_MAM")
		)
		(pad "2" smd circle
			(at -0.40005 0 90)
			(size 0 0)
			(layers "B.Cu" "B.Mask" "B.Paste")
			(net "GND")
		)
	)
	(footprint ""
		(layer "B.Cu")
		(at 238.064294 -247.691148 180)
		(property "Reference" "C1883"
			(at 0 0 0)
			(layer "B.SilkS")
			(hide yes)
			(effects
				(font
					(size 1.27 1.27)
				)
				(justify mirror)
			)
		)
		(property "Value" ""
			(at 0 0 0)
			(layer "B.Fab")
			(effects
				(font
					(size 1.27 1.27)
				)
				(justify mirror)
			)
		)
		(duplicate_pad_numbers_are_jumpers no)
		(fp_line
			(start 1.524 0.762)
			(end 1.524 -0.762)
			(stroke
				(width 0.1524)
				(type default)
			)
			(layer "B.SilkS")
		)
		(fp_line
			(start 1.524 -0.762)
			(end -1.524 -0.762)
			(stroke
				(width 0.1524)
				(type default)
			)
			(layer "B.SilkS")
		)
		(fp_line
			(start -1.524 0.762)
			(end 1.524 0.762)
			(stroke
				(width 0.1524)
				(type default)
			)
			(layer "B.SilkS")
		)
		(fp_line
			(start -1.524 -0.762)
			(end -1.524 0.762)
			(stroke
				(width 0.1524)
				(type default)
			)
			(layer "B.SilkS")
		)
		(fp_line
			(start 1.1049 0.724916)
			(end -1.1049 0.724916)
			(stroke
				(width 0.1)
				(type default)
			)
			(layer "B.Fab")
		)
		(fp_line
			(start 1.1049 -0.724916)
			(end 1.1049 0.724916)
			(stroke
				(width 0.1)
				(type default)
			)
			(layer "B.Fab")
		)
		(fp_line
			(start -1.1049 0.724916)
			(end -1.1049 -0.724916)
			(stroke
				(width 0.1)
				(type default)
			)
			(layer "B.Fab")
		)
		(fp_line
			(start -1.1049 -0.724916)
			(end 1.1049 -0.724916)
			(stroke
				(width 0.1)
				(type default)
			)
			(layer "B.Fab")
		)
		(pad "1" smd rect
			(at 0.889 0 180)
			(size 1.016 1.27)
			(layers "B.Cu" "B.Mask" "B.Paste")
			(net "VFG3P3_CLK_GEN")
		)
		(pad "2" smd rect
			(at -0.889 0 180)
			(size 1.016 1.27)
			(layers "B.Cu" "B.Mask" "B.Paste")
			(net "GND")
		)
	)
)
